# T6G (Grand Teton) — schematic netlist excerpt (pin names and nets, part order shuffled) for the footprints in the layout excerpt that follows; sources: Cadence DE-HDL packaged netlist, KiCad conversion of 04192023_DAF0TMB3IC0_F0TG_MB_C_brd_V02_OCP.brd

PC157_2  Q_CAP  22UF 16V 20% X6S  pkg C0805  page 205 : A = SW_P12V_AUX_PVDDIO_P0_FLT ; B = GND
C978  Q_CAP  1UF 4V 20% X6S  pkg 0201  page 301 : A = P0V9_CPU0_RT2_2A ; B = GND
C1036  Q_CAP  10UF 6.3V 20% X6S  pkg C0402  page 312 : A = P0V9_CPU0_RT3_2A ; B = GND

(kicad_pcb
	(version 20260206)
	(generator "pcbnew")
	(generator_version "10.0")
	(general
		(thickness 1.6)
		(legacy_teardrops no)
	)
	(paper "A4")
	(title_block
		(title "04192023_DAF0TMB3IC0_F0TG_MB_C_brd_V02_OCP.brd")
		(comment 1 "Grand Teton / footprints 6738-6740 of 8354")
	)
	(layers
		(0 "F.Cu" signal "TOP")
		(4 "In1.Cu" signal "GND")
		(6 "In2.Cu" signal "IN1")
		(8 "In3.Cu" signal "GND1")
		(10 "In4.Cu" signal "IN2")
		(12 "In5.Cu" signal "GND2")
		(14 "In6.Cu" signal "IN3")
		(16 "In7.Cu" signal "GND3")
		(18 "In8.Cu" signal "VCC")
		(20 "In9.Cu" signal "VCC1")
		(22 "In10.Cu" signal "GND4")
		(24 "In11.Cu" signal "IN4")
		(26 "In12.Cu" signal "GND5")
		(28 "In13.Cu" signal "IN5")
		(30 "In14.Cu" signal "GND6")
		(32 "In15.Cu" signal "IN6")
		(34 "In16.Cu" signal "GND7")
		(2 "B.Cu" signal "BOTTOM")
		(9 "F.Adhes" user "F.Adhesive")
		(11 "B.Adhes" user "B.Adhesive")
		(13 "F.Paste" user "Package Geometry/Pastemask Top")
		(15 "B.Paste" user "Package Geometry/Pastemask Bottom")
		(5 "F.SilkS" user "Ref Des/Silkscreen Top")
		(7 "B.SilkS" user "Ref Des/Silkscreen Bottom")
		(1 "F.Mask" user "Board Geometry/Soldermask Top")
		(3 "B.Mask" user "Board Geometry/Soldermask Bottom")
		(17 "Dwgs.User" user "User.Drawings")
		(19 "Cmts.User" user "User.Comments")
		(21 "Eco1.User" user "User.Eco1")
		(23 "Eco2.User" user "User.Eco2")
		(25 "Edge.Cuts" user "Board Geometry/Outline")
		(27 "Margin" user)
		(31 "F.CrtYd" user "Package Geometry/Place Bound Top")
		(29 "B.CrtYd" user "Package Geometry/Place Bound Bottom")
		(35 "F.Fab" user "Ref Des/Assembly Top")
		(33 "B.Fab" user "Ref Des/Assembly Bottom")
	)
	(footprint ""
		(layer "B.Cu")
		(at 405.406352 -395.148562 90)
		(property "Reference" "C978"
			(at 0 0 90)
			(layer "B.SilkS")
			(hide yes)
			(effects
				(font
					(size 1.27 1.27)
				)
				(justify mirror)
			)
		)
		(property "Value" ""
			(at 0 0 90)
			(layer "B.Fab")
			(effects
				(font
					(size 1.27 1.27)
				)
				(justify mirror)
			)
		)
		(duplicate_pad_numbers_are_jumpers no)
		(fp_line
			(start 0.299974 -0.150114)
			(end -0.299974 -0.150114)
			(stroke
				(width 0.1)
				(type default)
			)
			(layer "B.Fab")
		)
		(fp_line
			(start -0.299974 -0.150114)
			(end -0.299974 0.150114)
			(stroke
				(width 0.1)
				(type default)
			)
			(layer "B.Fab")
		)
		(fp_line
			(start 0.299974 0.150114)
			(end 0.299974 -0.150114)
			(stroke
				(width 0.1)
				(type default)
			)
			(layer "B.Fab")
		)
		(fp_line
			(start -0.299974 0.150114)
			(end 0.299974 0.150114)
			(stroke
				(width 0.1)
				(type default)
			)
			(layer "B.Fab")
		)
		(pad "1" smd rect
			(at 0.2667 0 270)
			(size 0.3048 0.381)
			(layers "B.Cu" "B.Mask" "B.Paste")
			(net "P0V9_CPU0_RT2_2A")
		)
		(pad "2" smd rect
			(at -0.2667 0 270)
			(size 0.3048 0.381)
			(layers "B.Cu" "B.Mask" "B.Paste")
			(net "GND")
		)
	)
	(footprint ""
		(layer "B.Cu")
		(at 388.491222 -398.942052 90)
		(property "Reference" "C1036"
			(at 0 0 90)
			(layer "B.SilkS")
			(hide yes)
			(effects
				(font
					(size 1.27 1.27)
				)
				(justify mirror)
			)
		)
		(property "Value" ""
			(at 0 0 90)
			(layer "B.Fab")
			(effects
				(font
					(size 1.27 1.27)
				)
				(justify mirror)
			)
		)
		(duplicate_pad_numbers_are_jumpers no)
		(fp_line
			(start 0.7874 -0.4064)
			(end -0.7874 -0.4064)
			(stroke
				(width 0.1524)
				(type default)
			)
			(layer "B.SilkS")
		)
		(fp_line
			(start -0.7874 -0.4064)
			(end -0.7874 0.4064)
			(stroke
				(width 0.1524)
				(type default)
			)
			(layer "B.SilkS")
		)
		(fp_line
			(start 0.7874 0.4064)
			(end 0.7874 -0.4064)
			(stroke
				(width 0.1524)
				(type default)
			)
			(layer "B.SilkS")
		)
		(fp_line
			(start -0.7874 0.4064)
			(end 0.7874 0.4064)
			(stroke
				(width 0.1524)
				(type default)
			)
			(layer "B.SilkS")
		)
		(fp_line
			(start 0.67945 -0.305054)
			(end 0.12065 -0.305054)
			(stroke
				(width 0.1)
				(type default)
			)
			(layer "B.Fab")
		)
		(fp_line
			(start 0.12065 -0.305054)
			(end 0.12065 -0.2794)
			(stroke
				(width 0.1)
				(type default)
			)
			(layer "B.Fab")
		)
		(fp_line
			(start -0.12065 -0.3048)
			(end -0.67945 -0.3048)
			(stroke
				(width 0.1)
				(type default)
			)
			(layer "B.Fab")
		)
		(fp_line
			(start -0.67945 -0.3048)
			(end -0.67945 0.3048)
			(stroke
				(width 0.1)
				(type default)
			)
			(layer "B.Fab")
		)
		(fp_line
			(start 0.12065 -0.2794)
			(end -0.12065 -0.2794)
			(stroke
				(width 0.1)
				(type default)
			)
			(layer "B.Fab")
		)
		(fp_line
			(start -0.12065 -0.2794)
			(end -0.12065 -0.3048)
			(stroke
				(width 0.1)
				(type default)
			)
			(layer "B.Fab")
		)
		(fp_line
			(start 0.12065 0.2794)
			(end 0.12065 0.3048)
			(stroke
				(width 0.1)
				(type default)
			)
			(layer "B.Fab")
		)
		(fp_line
			(start -0.120396 0.2794)
			(end 0.12065 0.2794)
			(stroke
				(width 0.1)
				(type default)
			)
			(layer "B.Fab")
		)
		(fp_line
			(start 0.67945 0.3048)
			(end 0.67945 -0.305054)
			(stroke
				(width 0.1)
				(type default)
			)
			(layer "B.Fab")
		)
		(fp_line
			(start 0.12065 0.3048)
			(end 0.67945 0.3048)
			(stroke
				(width 0.1)
				(type default)
			)
			(layer "B.Fab")
		)
		(fp_line
			(start -0.120396 0.3048)
			(end -0.120396 0.2794)
			(stroke
				(width 0.1)
				(type default)
			)
			(layer "B.Fab")
		)
		(fp_line
			(start -0.67945 0.3048)
			(end -0.120396 0.3048)
			(stroke
				(width 0.1)
				(type default)
			)
			(layer "B.Fab")
		)
		(pad "1" smd circle
			(at 0.40005 0 270)
			(size 0 0)
			(layers "B.Cu" "B.Mask" "B.Paste")
			(net "P0V9_CPU0_RT3_2A")
		)
		(pad "2" smd circle
			(at -0.40005 0 270)
			(size 0 0)
			(layers "B.Cu" "B.Mask" "B.Paste")
			(net "GND")
		)
	)
	(footprint ""
		(layer "B.Cu")
		(at 293.12997 -350.65589 -90)
		(property "Reference" "PC157_2"
			(at 0 0 90)
			(layer "B.SilkS")
			(hide yes)
			(effects
				(font
					(size 1.27 1.27)
				)
				(justify mirror)
			)
		)
		(property "Value" ""
			(at 0 0 90)
			(layer "B.Fab")
			(effects
				(font
					(size 1.27 1.27)
				)
				(justify mirror)
			)
		)
		(duplicate_pad_numbers_are_jumpers no)
		(fp_line
			(start -1.524 0.762)
			(end 1.524 0.762)
			(stroke
				(width 0.1524)
				(type default)
			)
			(layer "B.SilkS")
		)
		(fp_line
			(start 1.524 0.762)
			(end 1.524 -0.762)
			(stroke
				(width 0.1524)
				(type default)
			)
			(layer "B.SilkS")
		)
		(fp_line
			(start -1.524 -0.762)
			(end -1.524 0.762)
			(stroke
				(width 0.1524)
				(type default)
			)
			(layer "B.SilkS")
		)
		(fp_line
			(start 1.524 -0.762)
			(end -1.524 -0.762)
			(stroke
				(width 0.1524)
				(type default)
			)
			(layer "B.SilkS")
		)
		(fp_line
			(start -1.1049 0.724916)
			(end -1.1049 -0.724916)
			(stroke
				(width 0.1)
				(type default)
			)
			(layer "B.Fab")
		)
		(fp_line
			(start 1.1049 0.724916)
			(end -1.1049 0.724916)
			(stroke
				(width 0.1)
				(type default)
			)
			(layer "B.Fab")
		)
		(fp_line
			(start -1.1049 -0.724916)
			(end 1.1049 -0.724916)
			(stroke
				(width 0.1)
				(type default)
			)
			(layer "B.Fab")
		)
		(fp_line
			(start 1.1049 -0.724916)
			(end 1.1049 0.724916)
			(stroke
				(width 0.1)
				(type default)
			)
			(layer "B.Fab")
		)
		(pad "1" smd rect
			(at 0.889 0 270)
			(size 1.016 1.27)
			(layers "B.Cu" "B.Mask" "B.Paste")
			(net "SW_P12V_AUX_PVDDIO_P0_FLT")
		)
		(pad "2" smd rect
			(at -0.889 0 270)
			(size 1.016 1.27)
			(layers "B.Cu" "B.Mask" "B.Paste")
			(net "GND")
		)
	)
)
